(kicad_pcb
	(version 20241229)
	(generator "pcbnew")
	(generator_version "9.0")
	(general
		(thickness 1.61)
		(legacy_teardrops no)
	)
	(paper "A3")
	(title_block
		(title "RDIMM DDR5 Tester")
		(date "2026-05-21")
		(rev "2.2.0")
		(company "Antmicro")
		(comment 9 "footprints 82-86 of 796")
	)
	(layers
		(0 "F.Cu" signal)
		(4 "In1.Cu" power)
		(6 "In2.Cu" mixed)
		(8 "In3.Cu" power)
		(10 "In4.Cu" mixed)
		(12 "In5.Cu" power)
		(14 "In6.Cu" mixed)
		(16 "In7.Cu" power)
		(18 "In8.Cu" power)
		(20 "In9.Cu" mixed)
		(22 "In10.Cu" power)
		(2 "B.Cu" signal)
		(9 "F.Adhes" user "F.Adhesive")
		(11 "B.Adhes" user "B.Adhesive")
		(13 "F.Paste" user)
		(15 "B.Paste" user)
		(5 "F.SilkS" user "F.Silkscreen")
		(7 "B.SilkS" user "B.Silkscreen")
		(1 "F.Mask" user)
		(3 "B.Mask" user)
		(17 "Dwgs.User" user "User.Drawings")
		(19 "Cmts.User" user "User.Comments")
		(21 "Eco1.User" user "User.Eco1")
		(23 "Eco2.User" user "User.Eco2")
		(25 "Edge.Cuts" user)
		(27 "Margin" user)
		(31 "F.CrtYd" user "F.Courtyard")
		(29 "B.CrtYd" user "B.Courtyard")
		(35 "F.Fab" user)
		(33 "B.Fab" user)
	)
	(footprint "antmicro-footprints:NetTie-2_SMD_Pad0.127mm"
		(layer "F.Cu")
		(at 245.723 160.15 180)
		(descr "Net tie, 2 pin, 0.127mm  SMD pads")
		(tags "net tie")
		(property "Reference" "NT13"
			(at -0.128 -1.345 0)
			(layer "F.SilkS")
			(hide yes)
			(effects
				(font
					(size 0.7 0.7)
					(thickness 0.15)
				)
				(justify right bottom)
			)
		)
		(property "Value" "Net-Tie_P0.127mm"
			(at 0 1.199 0)
			(layer "F.Fab")
			(effects
				(font
					(size 0.7 0.7)
					(thickness 0.15)
				)
				(justify right bottom)
			)
		)
		(property "MPN" ""
			(at 0 0 180)
			(unlocked yes)
			(layer "F.Fab")
			(hide yes)
			(effects
				(font
					(size 1 1)
					(thickness 0.15)
				)
			)
		)
		(property "Manufacturer" ""
			(at 0 0 180)
			(unlocked yes)
			(layer "F.Fab")
			(hide yes)
			(effects
				(font
					(size 1 1)
					(thickness 0.15)
				)
			)
		)
		(property "Author" "Antmicro"
			(at 0 0 180)
			(unlocked yes)
			(layer "F.Fab")
			(hide yes)
			(effects
				(font
					(size 1 1)
					(thickness 0.15)
				)
			)
		)
		(property "License" "Apache-2.0"
			(at 0 0 180)
			(unlocked yes)
			(layer "F.Fab")
			(hide yes)
			(effects
				(font
					(size 1 1)
					(thickness 0.15)
				)
			)
		)
		(property ki_fp_filters "Net*Tie*")
		(sheetname "/Supply/DC-DC IO/")
		(sheetfile "dc-dc-io.kicad_sch")
		(attr through_hole exclude_from_pos_files exclude_from_bom)
		(net_tie_pad_groups "1, 2")
		(fp_poly
			(pts
				(xy -0.0635 -0.0635) (xy 0.0625 -0.0635) (xy 0.0625 0.0635) (xy -0.0635 0.0635)
			)
			(stroke
				(width 0)
				(type solid)
			)
			(fill yes)
			(layer "F.Cu")
		)
		(fp_poly
			(pts
				(xy 0.2 -0.16) (xy 0.29 -0.07) (xy 0.29 0.07) (xy 0.2 0.16) (xy -0.2 0.16) (xy -0.29 0.07) (xy -0.29 -0.06)
				(xy -0.19 -0.16)
			)
			(stroke
				(width 0.05)
				(type solid)
			)
			(fill no)
			(layer "F.CrtYd")
		)
		(fp_text user "Author: Antmicro"
			(at -0.128 4.4 180)
			(layer "F.Fab")
			(effects
				(font
					(size 0.7 0.7)
					(thickness 0.15)
				)
				(justify left bottom)
			)
		)
		(fp_text user "${REFERENCE}"
			(at -0.128 3.2 180)
			(layer "F.Fab")
			(effects
				(font
					(size 0.7 0.7)
					(thickness 0.15)
				)
				(justify left bottom)
			)
		)
		(fp_text user "License: Apache-2.0"
			(at -0.128 5.6 180)
			(layer "F.Fab")
			(effects
				(font
					(size 0.7 0.7)
					(thickness 0.15)
				)
				(justify left bottom)
			)
		)
		(pad "1" smd roundrect
			(at -0.127 0)
			(size 0.127 0.127)
			(layers "F.Cu")
			(roundrect_rratio 0.5)
			(chamfer_ratio 0)
			(chamfer top_left bottom_left)
			(net 693 "/Supply/DC-DC IO/3V3_SEN_-")
			(pinfunction "1")
			(pintype "passive")
		)
		(pad "2" smd roundrect
			(at 0.126 0 180)
			(size 0.127 0.127)
			(layers "F.Cu")
			(roundrect_rratio 0.5)
			(chamfer_ratio 0)
			(chamfer top_left bottom_left)
			(net 151 "+3V3")
			(pinfunction "2")
			(pintype "passive")
		)
	)
	(footprint "antmicro-footprints:C_0402_1005Metric"
		(layer "F.Cu")
		(at 118.19 145.61)
		(descr "Capacitor SMD 0402")
		(tags "capacitor SMD 0402")
		(property "Reference" "C300"
			(at -3.815 0.44 0)
			(layer "F.SilkS")
			(effects
				(font
					(size 0.7 0.7)
					(thickness 0.15)
				)
				(justify left bottom)
			)
		)
		(property "Value" "C_100n_0402"
			(at -1.022927 2.155213 0)
			(layer "F.Fab")
			(effects
				(font
					(size 0.7 0.7)
					(thickness 0.15)
				)
				(justify left bottom)
			)
		)
		(property "Datasheet" "https://www.murata.com/products/productdetail?partno=GRM155R61H104KE14%23"
			(at 0 0 0)
			(layer "F.Fab")
			(hide yes)
			(effects
				(font
					(size 1.27 1.27)
					(thickness 0.15)
				)
			)
		)
		(property "Manufacturer" "Murata"
			(at 0 0 0)
			(unlocked yes)
			(layer "F.Fab")
			(hide yes)
			(effects
				(font
					(size 1 1)
					(thickness 0.15)
				)
			)
		)
		(property "MPN" "GRM155R61H104KE14D"
			(at 0 0 0)
			(unlocked yes)
			(layer "F.Fab")
			(hide yes)
			(effects
				(font
					(size 1 1)
					(thickness 0.15)
				)
			)
		)
		(property "Val" "100n"
			(at 0 0 0)
			(unlocked yes)
			(layer "F.Fab")
			(hide yes)
			(effects
				(font
					(size 1 1)
					(thickness 0.15)
				)
			)
		)
		(property "License" "Apache-2.0"
			(at 0 0 0)
			(unlocked yes)
			(layer "F.Fab")
			(hide yes)
			(effects
				(font
					(size 1 1)
					(thickness 0.15)
				)
			)
		)
		(property "Author" "Antmicro"
			(at 0 0 0)
			(unlocked yes)
			(layer "F.Fab")
			(hide yes)
			(effects
				(font
					(size 1 1)
					(thickness 0.15)
				)
			)
		)
		(property "Voltage" "50V"
			(at 0 0 0)
			(unlocked yes)
			(layer "F.Fab")
			(hide yes)
			(effects
				(font
					(size 1 1)
					(thickness 0.15)
				)
			)
		)
		(property "Dielectric" "X5R"
			(at 0 0 0)
			(unlocked yes)
			(layer "F.Fab")
			(hide yes)
			(effects
				(font
					(size 1 1)
					(thickness 0.15)
				)
			)
		)
		(sheetname "/HDMI + SD Card/")
		(sheetfile "hdmi-sd-card.kicad_sch")
		(attr smd)
		(fp_rect
			(start -0.925 -0.47)
			(end 0.925 0.47)
			(stroke
				(width 0.05)
				(type default)
			)
			(fill no)
			(layer "F.CrtYd")
		)
		(fp_line
			(start -0.494 -0.25)
			(end 0.504 -0.25)
			(stroke
				(width 0.15)
				(type solid)
			)
			(layer "F.Fab")
		)
		(fp_line
			(start -0.494 0.248)
			(end -0.494 -0.25)
			(stroke
				(width 0.15)
				(type solid)
			)
			(layer "F.Fab")
		)
		(fp_line
			(start 0.504 -0.25)
			(end 0.504 0.248)
			(stroke
				(width 0.15)
				(type solid)
			)
			(layer "F.Fab")
		)
		(fp_line
			(start 0.504 0.248)
			(end -0.494 0.248)
			(stroke
				(width 0.15)
				(type solid)
			)
			(layer "F.Fab")
		)
		(fp_text user "License: Apache-2.0"
			(at -0.939 5.799 0)
			(layer "F.Fab")
			(effects
				(font
					(size 0.7 0.7)
					(thickness 0.15)
				)
				(justify left bottom)
			)
		)
		(fp_text user "${REFERENCE}"
			(at -0.939 4.599 0)
			(layer "F.Fab")
			(effects
				(font
					(size 0.7 0.7)
					(thickness 0.15)
				)
				(justify left bottom)
			)
		)
		(fp_text user "Author: Antmicro"
			(at -0.939 3.399 0)
			(layer "F.Fab")
			(effects
				(font
					(size 0.7 0.7)
					(thickness 0.15)
				)
				(justify left bottom)
			)
		)
		(pad "1" smd roundrect
			(at -0.48 0)
			(size 0.59 0.64)
			(layers "F.Cu" "F.Mask" "F.Paste")
			(roundrect_rratio 0.25)
			(net 1 "GND")
			(pintype "passive")
		)
		(pad "2" smd roundrect
			(at 0.48 0)
			(size 0.59 0.64)
			(layers "F.Cu" "F.Mask" "F.Paste")
			(roundrect_rratio 0.25)
			(net 322 "Net-(C300-Pad2)")
			(pintype "passive")
		)
	)
	(footprint "antmicro-footprints:R_1206_3216Metric"
		(layer "F.Cu")
		(at 246.279999 150.45 180)
		(property "Reference" "R146"
			(at -3.530001 1.38 0)
			(layer "F.SilkS")
			(effects
				(font
					(size 0.7 0.7)
					(thickness 0.15)
				)
				(justify right bottom)
			)
		)
		(property "Value" "R_0R01_1206"
			(at -2.422356 2.103591 0)
			(layer "F.Fab")
			(effects
				(font
					(size 0.7 0.7)
					(thickness 0.15)
				)
				(justify right bottom)
			)
		)
		(property "Datasheet" "https://www.yageo.com/upload/media/product/productsearch/datasheet/rchip/PYu-RL_Group_521_RoHS_L_2.pdf"
			(at 0 0 180)
			(layer "F.Fab")
			(hide yes)
			(effects
				(font
					(size 1.27 1.27)
					(thickness 0.15)
				)
			)
		)
		(property "Manufacturer" "YAGEO"
			(at 0 0 180)
			(unlocked yes)
			(layer "F.Fab")
			(hide yes)
			(effects
				(font
					(size 1 1)
					(thickness 0.15)
				)
			)
		)
		(property "MPN" "RL1206FR-7W0R01L"
			(at 0 0 180)
			(unlocked yes)
			(layer "F.Fab")
			(hide yes)
			(effects
				(font
					(size 1 1)
					(thickness 0.15)
				)
			)
		)
		(property "Val" "0R01"
			(at 0 0 180)
			(unlocked yes)
			(layer "F.Fab")
			(hide yes)
			(effects
				(font
					(size 1 1)
					(thickness 0.15)
				)
			)
		)
		(property "License" "Apache-2.0"
			(at 0 0 180)
			(unlocked yes)
			(layer "F.Fab")
			(hide yes)
			(effects
				(font
					(size 1 1)
					(thickness 0.15)
				)
			)
		)
		(property "Author" "Antmicro"
			(at 0 0 180)
			(unlocked yes)
			(layer "F.Fab")
			(hide yes)
			(effects
				(font
					(size 1 1)
					(thickness 0.15)
				)
			)
		)
		(property "Tolerance" "1%"
			(at 0 0 180)
			(unlocked yes)
			(layer "F.Fab")
			(hide yes)
			(effects
				(font
					(size 1 1)
					(thickness 0.15)
				)
			)
		)
		(sheetname "/Supply/DC-DC IO/")
		(sheetfile "dc-dc-io.kicad_sch")
		(attr smd)
		(fp_line
			(start 0.8 0.901)
			(end -0.8 0.901)
			(stroke
				(width 0.15)
				(type solid)
			)
			(layer "F.SilkS")
		)
		(fp_line
			(start 0.8 -0.899)
			(end -0.8 -0.899)
			(stroke
				(width 0.15)
				(type solid)
			)
			(layer "F.SilkS")
		)
		(fp_rect
			(start -2.325 -1.15)
			(end 2.325 1.15)
			(stroke
				(width 0.05)
				(type default)
			)
			(fill no)
			(layer "F.CrtYd")
		)
		(fp_line
			(start 1.6 -0.802)
			(end 1.6 0.8)
			(stroke
				(width 0.15)
				(type solid)
			)
			(layer "F.Fab")
		)
		(fp_line
			(start -1.601 0.8)
			(end 1.6 0.8)
			(stroke
				(width 0.15)
				(type solid)
			)
			(layer "F.Fab")
		)
		(fp_line
			(start -1.601 -0.802)
			(end 1.6 -0.802)
			(stroke
				(width 0.15)
				(type solid)
			)
			(layer "F.Fab")
		)
		(fp_line
			(start -1.601 -0.802)
			(end -1.601 0.8)
			(stroke
				(width 0.15)
				(type solid)
			)
			(layer "F.Fab")
		)
		(fp_text user "License: Apache-2.0"
			(at -2.401 6.3 180)
			(layer "F.Fab")
			(effects
				(font
					(size 0.7 0.7)
					(thickness 0.15)
				)
				(justify left bottom)
			)
		)
		(fp_text user "${REFERENCE}"
			(at -2.401 3.5 180)
			(layer "F.Fab")
			(effects
				(font
					(size 0.7 0.7)
					(thickness 0.15)
				)
				(justify left bottom)
			)
		)
		(fp_text user "Author: Antmicro"
			(at -2.401 4.899 180)
			(layer "F.Fab")
			(effects
				(font
					(size 0.7 0.7)
					(thickness 0.15)
				)
				(justify left bottom)
			)
		)
		(pad "1" smd roundrect
			(at -1.5 0.001 180)
			(size 1.15 1.8)
			(layers "F.Cu" "F.Mask" "F.Paste")
			(roundrect_rratio 0.25)
			(net 46 "/Supply/DC-DC IO/5V_local")
			(pintype "passive")
		)
		(pad "2" smd roundrect
			(at 1.5 0.001 180)
			(size 1.15 1.8)
			(layers "F.Cu" "F.Mask" "F.Paste")
			(roundrect_rratio 0.25)
			(net 152 "+5V")
			(pintype "passive")
		)
	)
	(footprint "antmicro-footprints:NetTie-2_SMD_Pad0.127mm"
		(layer "F.Cu")
		(at 246.687 167.948)
		(descr "Net tie, 2 pin, 0.127mm  SMD pads")
		(tags "net tie")
		(property "Reference" "NT2"
			(at -0.128 -1.345 0)
			(layer "F.SilkS")
			(hide yes)
			(effects
				(font
					(size 0.7 0.7)
					(thickness 0.15)
				)
				(justify left bottom)
			)
		)
		(property "Value" "Net-Tie_P0.127mm"
			(at 0 1.199 0)
			(layer "F.Fab")
			(effects
				(font
					(size 0.7 0.7)
					(thickness 0.15)
				)
				(justify left bottom)
			)
		)
		(property "MPN" ""
			(at 0 0 0)
			(unlocked yes)
			(layer "F.Fab")
			(hide yes)
			(effects
				(font
					(size 1 1)
					(thickness 0.15)
				)
			)
		)
		(property "Manufacturer" ""
			(at 0 0 0)
			(unlocked yes)
			(layer "F.Fab")
			(hide yes)
			(effects
				(font
					(size 1 1)
					(thickness 0.15)
				)
			)
		)
		(property "Author" "Antmicro"
			(at 0 0 0)
			(unlocked yes)
			(layer "F.Fab")
			(hide yes)
			(effects
				(font
					(size 1 1)
					(thickness 0.15)
				)
			)
		)
		(property "License" "Apache-2.0"
			(at 0 0 0)
			(unlocked yes)
			(layer "F.Fab")
			(hide yes)
			(effects
				(font
					(size 1 1)
					(thickness 0.15)
				)
			)
		)
		(property ki_fp_filters "Net*Tie*")
		(sheetname "/Supply/DC-DC AUX, MGT/")
		(sheetfile "dc-dc-aux-mgt.kicad_sch")
		(attr through_hole exclude_from_pos_files exclude_from_bom)
		(net_tie_pad_groups "1, 2")
		(fp_poly
			(pts
				(xy -0.0635 -0.0635) (xy 0.0625 -0.0635) (xy 0.0625 0.0635) (xy -0.0635 0.0635)
			)
			(stroke
				(width 0)
				(type solid)
			)
			(fill yes)
			(layer "F.Cu")
		)
		(fp_poly
			(pts
				(xy 0.2 -0.16) (xy 0.29 -0.07) (xy 0.29 0.07) (xy 0.2 0.16) (xy -0.2 0.16) (xy -0.29 0.07) (xy -0.29 -0.06)
				(xy -0.19 -0.16)
			)
			(stroke
				(width 0.05)
				(type solid)
			)
			(fill no)
			(layer "F.CrtYd")
		)
		(fp_text user "License: Apache-2.0"
			(at -0.128 5.6 0)
			(layer "F.Fab")
			(effects
				(font
					(size 0.7 0.7)
					(thickness 0.15)
				)
				(justify left bottom)
			)
		)
		(fp_text user "${REFERENCE}"
			(at -0.128 3.2 0)
			(layer "F.Fab")
			(effects
				(font
					(size 0.7 0.7)
					(thickness 0.15)
				)
				(justify left bottom)
			)
		)
		(fp_text user "Author: Antmicro"
			(at -0.128 4.4 0)
			(layer "F.Fab")
			(effects
				(font
					(size 0.7 0.7)
					(thickness 0.15)
				)
				(justify left bottom)
			)
		)
		(pad "1" smd roundrect
			(at -0.127 0 180)
			(size 0.127 0.127)
			(layers "F.Cu")
			(roundrect_rratio 0.5)
			(chamfer_ratio 0)
			(chamfer top_left bottom_left)
			(net 682 "/Supply/DC-DC AUX, MGT/MGTAVTT_SEN_+")
			(pinfunction "1")
			(pintype "passive")
		)
		(pad "2" smd roundrect
			(at 0.126 0)
			(size 0.127 0.127)
			(layers "F.Cu")
			(roundrect_rratio 0.5)
			(chamfer_ratio 0)
			(chamfer top_left bottom_left)
			(net 48 "/Supply/DC-DC AUX, MGT/MGTAVTT_local")
			(pinfunction "2")
			(pintype "passive")
		)
	)
	(footprint "antmicro-footprints:C_0603_1608Metric"
		(layer "F.Cu")
		(at 257.5 160.571)
		(descr "Capacitor SMD 0603")
		(tags "capacitor 0603")
		(property "Reference" "C193"
			(at 1.0445 0.029 0)
			(layer "F.SilkS")
			(effects
				(font
					(size 0.7 0.7)
					(thickness 0.15)
				)
				(justify left bottom)
			)
		)
		(property "Value" "C_22u_0603"
			(at -1.42757 1.770288 0)
			(layer "F.Fab")
			(effects
				(font
					(size 0.7 0.7)
					(thickness 0.15)
				)
				(justify left bottom)
			)
		)
		(property "Datasheet" "https://www.murata.com/products/productdetail?partno=GRM188R60J226MEA0%23"
			(at 0 0 0)
			(layer "F.Fab")
			(hide yes)
			(effects
				(font
					(size 1.27 1.27)
					(thickness 0.15)
				)
			)
		)
		(property "Manufacturer" "Murata"
			(at 0 0 0)
			(unlocked yes)
			(layer "F.Fab")
			(hide yes)
			(effects
				(font
					(size 1 1)
					(thickness 0.15)
				)
			)
		)
		(property "MPN" "GRM188R60J226MEA0D"
			(at 0 0 0)
			(unlocked yes)
			(layer "F.Fab")
			(hide yes)
			(effects
				(font
					(size 1 1)
					(thickness 0.15)
				)
			)
		)
		(property "Val" "22u"
			(at 0 0 0)
			(unlocked yes)
			(layer "F.Fab")
			(hide yes)
			(effects
				(font
					(size 1 1)
					(thickness 0.15)
				)
			)
		)
		(property "License" "Apache-2.0"
			(at 0 0 0)
			(unlocked yes)
			(layer "F.Fab")
			(hide yes)
			(effects
				(font
					(size 1 1)
					(thickness 0.15)
				)
			)
		)
		(property "Author" "Antmicro"
			(at 0 0 0)
			(unlocked yes)
			(layer "F.Fab")
			(hide yes)
			(effects
				(font
					(size 1 1)
					(thickness 0.15)
				)
			)
		)
		(property "Voltage" ""
			(at 0 0 0)
			(unlocked yes)
			(layer "F.Fab")
			(hide yes)
			(effects
				(font
					(size 1 1)
					(thickness 0.15)
				)
			)
		)
		(property "Dielectric" ""
			(at 0 0 0)
			(unlocked yes)
			(layer "F.Fab")
			(hide yes)
			(effects
				(font
					(size 1 1)
					(thickness 0.15)
				)
			)
		)
		(sheetname "/Supply/DC-DC IO/")
		(sheetfile "dc-dc-io.kicad_sch")
		(attr smd)
		(fp_line
			(start -0.15 -0.4)
			(end 0.15 -0.4)
			(stroke
				(width 0.15)
				(type solid)
			)
			(layer "F.SilkS")
		)
		(fp_line
			(start -0.15 0.4)
			(end 0.15 0.4)
			(stroke
				(width 0.15)
				(type solid)
			)
			(layer "F.SilkS")
		)
		(fp_rect
			(start -1.25 -0.65)
			(end 1.25 0.65)
			(stroke
				(width 0.05)
				(type solid)
			)
			(fill no)
			(layer "F.CrtYd")
		)
		(fp_rect
			(start -0.8 -0.4)
			(end 0.8 0.4)
			(stroke
				(width 0.15)
				(type solid)
			)
			(fill no)
			(layer "F.Fab")
		)
		(fp_text user "${REFERENCE}"
			(at -1.682 3.895 0)
			(layer "F.Fab")
			(effects
				(font
					(size 0.7 0.7)
					(thickness 0.15)
				)
				(justify left bottom)
			)
		)
		(fp_text user "License: Apache-2.0"
			(at -1.682 5.895 0)
			(layer "F.Fab")
			(effects
				(font
					(size 0.7 0.7)
					(thickness 0.15)
				)
				(justify left bottom)
			)
		)
		(fp_text user "Author: Antmicro"
			(at -1.682 4.894 0)
			(layer "F.Fab")
			(effects
				(font
					(size 0.7 0.7)
					(thickness 0.15)
				)
				(justify left bottom)
			)
		)
		(pad "1" smd roundrect
			(at -0.7 0)
			(size 0.8 1)
			(layers "F.Cu" "F.Mask" "F.Paste")
			(roundrect_rratio 0.2)
			(net 1 "GND")
			(pintype "passive")
		)
		(pad "2" smd roundrect
			(at 0.7 0)
			(size 0.8 1)
			(layers "F.Cu" "F.Mask" "F.Paste")
			(roundrect_rratio 0.2)
			(net 159 "/Supply/DC-DC IO/1V2_local")
			(pintype "passive")
		)
	)
)
